(kicad_pcb
	(version 20260206)
	(generator "pcbnew")
	(generator_version "10.0")
	(general
		(thickness 1.6)
		(legacy_teardrops no)
	)
	(paper "A4")
	(title_block
		(title "04192023_DAF0TMB3IC0_F0TG_MB_C_brd_V02_OCP.brd")
		(comment 1 "Grand Teton / footprints 3580-3585 of 8354")
	)
	(layers
		(0 "F.Cu" signal "TOP")
		(4 "In1.Cu" signal "GND")
		(6 "In2.Cu" signal "IN1")
		(8 "In3.Cu" signal "GND1")
		(10 "In4.Cu" signal "IN2")
		(12 "In5.Cu" signal "GND2")
		(14 "In6.Cu" signal "IN3")
		(16 "In7.Cu" signal "GND3")
		(18 "In8.Cu" signal "VCC")
		(20 "In9.Cu" signal "VCC1")
		(22 "In10.Cu" signal "GND4")
		(24 "In11.Cu" signal "IN4")
		(26 "In12.Cu" signal "GND5")
		(28 "In13.Cu" signal "IN5")
		(30 "In14.Cu" signal "GND6")
		(32 "In15.Cu" signal "IN6")
		(34 "In16.Cu" signal "GND7")
		(2 "B.Cu" signal "BOTTOM")
		(9 "F.Adhes" user "F.Adhesive")
		(11 "B.Adhes" user "B.Adhesive")
		(13 "F.Paste" user "Package Geometry/Pastemask Top")
		(15 "B.Paste" user "Package Geometry/Pastemask Bottom")
		(5 "F.SilkS" user "Ref Des/Silkscreen Top")
		(7 "B.SilkS" user "Ref Des/Silkscreen Bottom")
		(1 "F.Mask" user "Board Geometry/Soldermask Top")
		(3 "B.Mask" user "Board Geometry/Soldermask Bottom")
		(17 "Dwgs.User" user "User.Drawings")
		(19 "Cmts.User" user "User.Comments")
		(21 "Eco1.User" user "User.Eco1")
		(23 "Eco2.User" user "User.Eco2")
		(25 "Edge.Cuts" user "Board Geometry/Outline")
		(27 "Margin" user)
		(31 "F.CrtYd" user "Package Geometry/Place Bound Top")
		(29 "B.CrtYd" user "Package Geometry/Place Bound Bottom")
		(35 "F.Fab" user "Ref Des/Assembly Top")
		(33 "B.Fab" user "Ref Des/Assembly Bottom")
	)
	(footprint ""
		(layer "F.Cu")
		(at 78.764638 -334.99298)
		(property "Reference" "PU5"
			(at -0.659638 -8.51535 0)
			(unlocked yes)
			(layer "F.SilkS")
			(effects
				(font
					(size 0.7874 0.5842)
					(thickness 0.1524)
				)
				(justify left)
			)
		)
		(property "Value" ""
			(at 0 0 0)
			(layer "F.Fab")
			(effects
				(font
					(size 1.27 1.27)
				)
			)
		)
		(duplicate_pad_numbers_are_jumpers no)
		(fp_line
			(start -2.500122 -2.999994)
			(end -2.24409 -2.999994)
			(stroke
				(width 0.1524)
				(type default)
			)
			(layer "F.SilkS")
		)
		(fp_line
			(start -2.500122 -2.529078)
			(end -2.500122 -2.999994)
			(stroke
				(width 0.1524)
				(type default)
			)
			(layer "F.SilkS")
		)
		(fp_line
			(start -2.500122 0.6604)
			(end -2.500122 0.229108)
			(stroke
				(width 0.1524)
				(type default)
			)
			(layer "F.SilkS")
		)
		(fp_line
			(start -2.500122 2.999994)
			(end -2.500122 2.339594)
			(stroke
				(width 0.1524)
				(type default)
			)
			(layer "F.SilkS")
		)
		(fp_line
			(start -2.2987 2.999994)
			(end -2.500122 2.999994)
			(stroke
				(width 0.1524)
				(type default)
			)
			(layer "F.SilkS")
		)
		(fp_line
			(start 2.31394 -2.999994)
			(end 2.500122 -2.999994)
			(stroke
				(width 0.1524)
				(type default)
			)
			(layer "F.SilkS")
		)
		(fp_line
			(start 2.500122 -2.999994)
			(end 2.500122 -2.44348)
			(stroke
				(width 0.1524)
				(type default)
			)
			(layer "F.SilkS")
		)
		(fp_line
			(start 2.500122 2.339594)
			(end 2.500122 2.999994)
			(stroke
				(width 0.1524)
				(type default)
			)
			(layer "F.SilkS")
		)
		(fp_line
			(start 2.500122 2.999994)
			(end 2.2987 2.999994)
			(stroke
				(width 0.1524)
				(type default)
			)
			(layer "F.SilkS")
		)
		(fp_poly
			(pts
				(xy -2.7686 -2.321306) (xy -3.441954 -2.545842) (xy -2.993136 -2.994914)
			)
			(stroke
				(width 0)
				(type default)
			)
			(fill yes)
			(layer "F.SilkS")
		)
		(fp_line
			(start -2.500122 -2.999994)
			(end 2.500122 -2.999994)
			(stroke
				(width 0.1)
				(type default)
			)
			(layer "F.Fab")
		)
		(fp_line
			(start -2.500122 2.999994)
			(end -2.500122 -2.999994)
			(stroke
				(width 0.1)
				(type default)
			)
			(layer "F.Fab")
		)
		(fp_line
			(start 2.500122 -2.999994)
			(end 2.500122 2.999994)
			(stroke
				(width 0.1)
				(type default)
			)
			(layer "F.Fab")
		)
		(fp_line
			(start 2.500122 2.999994)
			(end -2.500122 2.999994)
			(stroke
				(width 0.1)
				(type default)
			)
			(layer "F.Fab")
		)
		(fp_poly
			(pts
				(xy -4.218432 -2.783078) (xy -4.218432 -1.767078) (xy -3.202432 -2.275078)
			)
			(stroke
				(width 0)
				(type default)
			)
			(fill yes)
			(layer "F.Fab")
		)
		(pad "1" smd rect
			(at -2.400046 -2.275078 90)
			(size 0.2286 0.6096)
			(layers "F.Cu" "F.Mask" "F.Paste")
			(net "PVDDCR_CPU1_P1_VOS2")
		)
		(pad "2" smd rect
			(at -2.400046 -1.82499 90)
			(size 0.2286 0.6096)
			(layers "F.Cu" "F.Mask" "F.Paste")
			(net "GND")
		)
		(pad "3" smd rect
			(at -2.400046 -1.374902 90)
			(size 0.2286 0.6096)
			(layers "F.Cu" "F.Mask" "F.Paste")
			(net "PVDDCR_CPU1_P1_VCC2")
		)
		(pad "4" smd rect
			(at -2.400046 -0.925068 90)
			(size 0.2286 0.6096)
			(layers "F.Cu" "F.Mask" "F.Paste")
			(net "PVDDCR_CPU1_P1_PVCC")
		)
		(pad "5" smd rect
			(at -2.400046 -0.47498 90)
			(size 0.2286 0.6096)
			(layers "F.Cu" "F.Mask" "F.Paste")
			(net "GND")
		)
		(pad "6" smd rect
			(at -2.400046 -0.024892 90)
			(size 0.2286 0.6096)
			(layers "F.Cu" "F.Mask" "F.Paste")
			(net "NC_PVDDCR_CPU1_P1_GL1_2")
		)
		(pad "7_9-20_24" smd circle
			(at 0 1.150112 90)
			(size 0 0)
			(layers "F.Cu" "F.Mask" "F.Paste")
			(net "GND")
		)
		(pad "10_19" smd rect
			(at 0 2.899918 90)
			(size 0.6096 4.318)
			(layers "F.Cu" "F.Mask" "F.Paste")
			(net "SW_PVDDCR_CPU1_P1_SW2")
		)
		(pad "25_29" smd rect
			(at 1.549908 -1.279906 270)
			(size 2.0574 2.3114)
			(layers "F.Cu" "F.Mask" "F.Paste")
			(net "SW_P12V_AUX_PVDDCR_CPU1_P1_FLT")
		)
		(pad "30" smd rect
			(at 2.05994 -2.899918)
			(size 0.2286 0.6096)
			(layers "F.Cu" "F.Mask" "F.Paste")
			(net "SW_P12V_AUX_PVDDCR_CPU1_P1_FLT")
		)
		(pad "31" smd rect
			(at 1.610106 -2.899918)
			(size 0.2286 0.6096)
			(layers "F.Cu" "F.Mask" "F.Paste")
			(net "NC_PVDDCR_CPU1_P1_DNC2")
		)
		(pad "32" smd rect
			(at 1.160018 -2.899918)
			(size 0.2286 0.6096)
			(layers "F.Cu" "F.Mask" "F.Paste")
			(net "SW_PVDDCR_CPU1_P1_BOOTR2")
		)
		(pad "33" smd rect
			(at 0.70993 -2.899918)
			(size 0.2286 0.6096)
			(layers "F.Cu" "F.Mask" "F.Paste")
			(net "SW_PVDDCR_CPU1_P1_BOOT2")
		)
		(pad "34" smd rect
			(at 0.260096 -2.899918)
			(size 0.2286 0.6096)
			(layers "F.Cu" "F.Mask" "F.Paste")
			(net "PVDDCR_CPU1_P1_PWM2")
		)
		(pad "35" smd rect
			(at -0.189992 -2.899918)
			(size 0.2286 0.6096)
			(layers "F.Cu" "F.Mask" "F.Paste")
			(net "PVDDCR_CPU1_P1_VCC2")
		)
		(pad "36" smd rect
			(at -0.64008 -2.899918)
			(size 0.2286 0.6096)
			(layers "F.Cu" "F.Mask" "F.Paste")
			(net "PVDDCR_CPU1_P1_TEMP0")
		)
		(pad "37" smd rect
			(at -1.089914 -2.899918)
			(size 0.2286 0.6096)
			(layers "F.Cu" "F.Mask" "F.Paste")
			(net "PVDDCR_CPU1_P1_LSET2")
		)
		(pad "38" smd rect
			(at -1.540002 -2.899918)
			(size 0.2286 0.6096)
			(layers "F.Cu" "F.Mask" "F.Paste")
			(net "PVDDCR_CPU1_P1_IMON2")
		)
		(pad "39" smd rect
			(at -1.99009 -2.899918)
			(size 0.2286 0.6096)
			(layers "F.Cu" "F.Mask" "F.Paste")
			(net "PVDDCR_CPU1_P1_VCCS")
		)
		(pad "40" smd rect
			(at -0.87503 -1.27508)
			(size 1.7526 1.9558)
			(layers "F.Cu" "F.Mask" "F.Paste")
			(net "GND")
		)
		(pad "41" smd rect
			(at -1.525016 0.249936 270)
			(size 0.3048 0.4572)
			(layers "F.Cu" "F.Mask" "F.Paste")
			(net "NC_PVDDCR_CPU1_P1_GL2_2")
		)
		(zone
			(layer "F.Cu")
			(hatch none 0.5)
			(connect_pads
				(clearance 0)
			)
			(min_thickness 0.25)
			(keepout
				(tracks not_allowed)
				(vias allowed)
				(pads allowed)
				(copperpour not_allowed)
				(footprints allowed)
			)
			(placement
				(enabled no)
				(sheetname "")
			)
			(fill
				(thermal_gap 0.5)
				(thermal_bridge_width 0.5)
				(island_removal_mode 0)
			)
			(polygon
				(pts
					(xy 76.264516 -332.394052) (xy 76.264516 -332.742286) (xy 81.26476 -332.742286) (xy 81.26476 -332.420976)
					(xy 80.974438 -332.420976) (xy 80.974438 -332.448662) (xy 76.554838 -332.448662) (xy 76.554838 -332.394052)
				)
			)
		)
		(zone
			(layer "F.Cu")
			(hatch none 0.5)
			(connect_pads
				(clearance 0)
			)
			(min_thickness 0.25)
			(keepout
				(tracks not_allowed)
				(vias allowed)
				(pads allowed)
				(copperpour not_allowed)
				(footprints allowed)
			)
			(placement
				(enabled no)
				(sheetname "")
			)
			(fill
				(thermal_gap 0.5)
				(thermal_bridge_width 0.5)
				(island_removal_mode 0)
			)
			(polygon
				(pts
					(xy 78.816708 -335.23936) (xy 78.816708 -337.29676) (xy 76.962508 -337.29676) (xy 76.962508 -337.055714)
					(xy 76.720192 -337.055714) (xy 76.720192 -337.537298) (xy 80.504538 -337.537298) (xy 80.504538 -337.352386)
					(xy 79.108046 -337.352386) (xy 79.108046 -335.193386) (xy 81.26476 -335.193386) (xy 81.26476 -334.943704)
					(xy 79.112364 -334.943704)
				)
			)
		)
	)
	(footprint ""
		(layer "F.Cu")
		(at 413.754062 -416.899344 -90)
		(property "Reference" "C6594"
			(at 0 0 270)
			(layer "F.SilkS")
			(hide yes)
			(effects
				(font
					(size 1.27 1.27)
				)
			)
		)
		(property "Value" ""
			(at 0 0 270)
			(layer "F.Fab")
			(effects
				(font
					(size 1.27 1.27)
				)
			)
		)
		(duplicate_pad_numbers_are_jumpers no)
		(fp_line
			(start -0.299974 0.150114)
			(end -0.299974 -0.150114)
			(stroke
				(width 0.1)
				(type default)
			)
			(layer "F.Fab")
		)
		(fp_line
			(start 0.299974 0.150114)
			(end -0.299974 0.150114)
			(stroke
				(width 0.1)
				(type default)
			)
			(layer "F.Fab")
		)
		(fp_line
			(start -0.299974 -0.150114)
			(end 0.299974 -0.150114)
			(stroke
				(width 0.1)
				(type default)
			)
			(layer "F.Fab")
		)
		(fp_line
			(start 0.299974 -0.150114)
			(end 0.299974 0.150114)
			(stroke
				(width 0.1)
				(type default)
			)
			(layer "F.Fab")
		)
		(pad "1" smd rect
			(at -0.2667 0 270)
			(size 0.3048 0.381)
			(layers "F.Cu" "F.Mask" "F.Paste")
			(net "P5E_CPU0_P2_TX_BUF_C_DN<14>")
		)
		(pad "2" smd rect
			(at 0.2667 0 270)
			(size 0.3048 0.381)
			(layers "F.Cu" "F.Mask" "F.Paste")
			(net "P5E_CPU0_P2_TX_BUF_DN<14>")
		)
	)
	(footprint ""
		(layer "F.Cu")
		(at 373.811292 -381.41783 -90)
		(property "Reference" "C890"
			(at 0 0 270)
			(layer "F.SilkS")
			(hide yes)
			(effects
				(font
					(size 1.27 1.27)
				)
			)
		)
		(property "Value" ""
			(at 0 0 270)
			(layer "F.Fab")
			(effects
				(font
					(size 1.27 1.27)
				)
			)
		)
		(duplicate_pad_numbers_are_jumpers no)
		(fp_line
			(start -0.299974 0.150114)
			(end -0.299974 -0.150114)
			(stroke
				(width 0.1)
				(type default)
			)
			(layer "F.Fab")
		)
		(fp_line
			(start 0.299974 0.150114)
			(end -0.299974 0.150114)
			(stroke
				(width 0.1)
				(type default)
			)
			(layer "F.Fab")
		)
		(fp_line
			(start -0.299974 -0.150114)
			(end 0.299974 -0.150114)
			(stroke
				(width 0.1)
				(type default)
			)
			(layer "F.Fab")
		)
		(fp_line
			(start 0.299974 -0.150114)
			(end 0.299974 0.150114)
			(stroke
				(width 0.1)
				(type default)
			)
			(layer "F.Fab")
		)
		(pad "1" smd rect
			(at -0.2667 0 270)
			(size 0.3048 0.381)
			(layers "F.Cu" "F.Mask" "F.Paste")
			(net "P5E_CPU0_P3_TX_C_DN<5>")
		)
		(pad "2" smd rect
			(at 0.2667 0 270)
			(size 0.3048 0.381)
			(layers "F.Cu" "F.Mask" "F.Paste")
			(net "P5E_CPU0_P3_TX_DN<5>")
		)
	)
	(footprint ""
		(layer "F.Cu")
		(at 52.413154 -370.57203 -90)
		(property "Reference" "C824"
			(at 0 0 270)
			(layer "F.SilkS")
			(hide yes)
			(effects
				(font
					(size 1.27 1.27)
				)
			)
		)
		(property "Value" ""
			(at 0 0 270)
			(layer "F.Fab")
			(effects
				(font
					(size 1.27 1.27)
				)
			)
		)
		(duplicate_pad_numbers_are_jumpers no)
		(fp_line
			(start -0.299974 0.150114)
			(end -0.299974 -0.150114)
			(stroke
				(width 0.1)
				(type default)
			)
			(layer "F.Fab")
		)
		(fp_line
			(start 0.299974 0.150114)
			(end -0.299974 0.150114)
			(stroke
				(width 0.1)
				(type default)
			)
			(layer "F.Fab")
		)
		(fp_line
			(start -0.299974 -0.150114)
			(end 0.299974 -0.150114)
			(stroke
				(width 0.1)
				(type default)
			)
			(layer "F.Fab")
		)
		(fp_line
			(start 0.299974 -0.150114)
			(end 0.299974 0.150114)
			(stroke
				(width 0.1)
				(type default)
			)
			(layer "F.Fab")
		)
		(pad "1" smd rect
			(at -0.2667 0 270)
			(size 0.3048 0.381)
			(layers "F.Cu" "F.Mask" "F.Paste")
			(net "P5E_CPU1_P0_TX_C_DN<6>")
		)
		(pad "2" smd rect
			(at 0.2667 0 270)
			(size 0.3048 0.381)
			(layers "F.Cu" "F.Mask" "F.Paste")
			(net "P5E_CPU1_P0_TX_DN<6>")
		)
	)
	(footprint ""
		(layer "F.Cu")
		(at 227.59162 -291.863526 180)
		(property "Reference" "PC6537"
			(at 0 0 180)
			(layer "F.SilkS")
			(hide yes)
			(effects
				(font
					(size 1.27 1.27)
				)
			)
		)
		(property "Value" ""
			(at 0 0 180)
			(layer "F.Fab")
			(effects
				(font
					(size 1.27 1.27)
				)
			)
		)
		(duplicate_pad_numbers_are_jumpers no)
		(fp_line
			(start 0.7874 0.4064)
			(end -0.7874 0.4064)
			(stroke
				(width 0.1524)
				(type default)
			)
			(layer "F.SilkS")
		)
		(fp_line
			(start 0.7874 -0.4064)
			(end 0.7874 0.4064)
			(stroke
				(width 0.1524)
				(type default)
			)
			(layer "F.SilkS")
		)
		(fp_line
			(start -0.7874 0.4064)
			(end -0.7874 -0.4064)
			(stroke
				(width 0.1524)
				(type default)
			)
			(layer "F.SilkS")
		)
		(fp_line
			(start -0.7874 -0.4064)
			(end 0.7874 -0.4064)
			(stroke
				(width 0.1524)
				(type default)
			)
			(layer "F.SilkS")
		)
		(fp_line
			(start 0.67945 0.3048)
			(end 0.120396 0.3048)
			(stroke
				(width 0.1)
				(type default)
			)
			(layer "F.Fab")
		)
		(fp_line
			(start 0.67945 -0.3048)
			(end 0.67945 0.3048)
			(stroke
				(width 0.1)
				(type default)
			)
			(layer "F.Fab")
		)
		(fp_line
			(start 0.12065 -0.2794)
			(end 0.12065 -0.3048)
			(stroke
				(width 0.1)
				(type default)
			)
			(layer "F.Fab")
		)
		(fp_line
			(start 0.12065 -0.3048)
			(end 0.67945 -0.3048)
			(stroke
				(width 0.1)
				(type default)
			)
			(layer "F.Fab")
		)
		(fp_line
			(start 0.120396 0.3048)
			(end 0.120396 0.2794)
			(stroke
				(width 0.1)
				(type default)
			)
			(layer "F.Fab")
		)
		(fp_line
			(start 0.120396 0.2794)
			(end -0.12065 0.2794)
			(stroke
				(width 0.1)
				(type default)
			)
			(layer "F.Fab")
		)
		(fp_line
			(start -0.12065 0.3048)
			(end -0.67945 0.3048)
			(stroke
				(width 0.1)
				(type default)
			)
			(layer "F.Fab")
		)
		(fp_line
			(start -0.12065 0.2794)
			(end -0.12065 0.3048)
			(stroke
				(width 0.1)
				(type default)
			)
			(layer "F.Fab")
		)
		(fp_line
			(start -0.12065 -0.2794)
			(end 0.12065 -0.2794)
			(stroke
				(width 0.1)
				(type default)
			)
			(layer "F.Fab")
		)
		(fp_line
			(start -0.12065 -0.305054)
			(end -0.12065 -0.2794)
			(stroke
				(width 0.1)
				(type default)
			)
			(layer "F.Fab")
		)
		(fp_line
			(start -0.67945 0.3048)
			(end -0.67945 -0.305054)
			(stroke
				(width 0.1)
				(type default)
			)
			(layer "F.Fab")
		)
		(fp_line
			(start -0.67945 -0.305054)
			(end -0.12065 -0.305054)
			(stroke
				(width 0.1)
				(type default)
			)
			(layer "F.Fab")
		)
		(pad "1" smd circle
			(at -0.40005 0 180)
			(size 0 0)
			(layers "F.Cu" "F.Mask" "F.Paste")
			(net "P1V8_RETIMER_CPU1_REF")
		)
		(pad "2" smd circle
			(at 0.40005 0 180)
			(size 0 0)
			(layers "F.Cu" "F.Mask" "F.Paste")
			(net "GND")
		)
	)
	(footprint ""
		(layer "F.Cu")
		(at 347.690694 -170.457114 180)
		(property "Reference" "PL70"
			(at 3.709924 7.921498 0)
			(unlocked yes)
			(layer "F.SilkS")
			(effects
				(font
					(size 0.7874 0.5842)
					(thickness 0.1524)
				)
				(justify left)
			)
		)
		(property "Value" ""
			(at 0 0 180)
			(layer "F.Fab")
			(effects
				(font
					(size 1.27 1.27)
				)
			)
		)
		(duplicate_pad_numbers_are_jumpers no)
		(fp_line
			(start 3.750056 5.500116)
			(end 3.750056 -5.500116)
			(stroke
				(width 0.1524)
				(type default)
			)
			(layer "F.SilkS")
		)
		(fp_line
			(start 3.750056 -5.500116)
			(end 2.393442 -5.500116)
			(stroke
				(width 0.1524)
				(type default)
			)
			(layer "F.SilkS")
		)
		(fp_line
			(start 2.393442 5.500116)
			(end 3.750056 5.500116)
			(stroke
				(width 0.1524)
				(type default)
			)
			(layer "F.SilkS")
		)
		(fp_line
			(start -2.393442 5.500116)
			(end -3.750056 5.500116)
			(stroke
				(width 0.1524)
				(type default)
			)
			(layer "F.SilkS")
		)
		(fp_line
			(start -3.750056 5.500116)
			(end -3.750056 -5.500116)
			(stroke
				(width 0.1524)
				(type default)
			)
			(layer "F.SilkS")
		)
		(fp_line
			(start -3.750056 -5.500116)
			(end -2.393442 -5.500116)
			(stroke
				(width 0.1524)
				(type default)
			)
			(layer "F.SilkS")
		)
		(fp_poly
			(pts
				(xy -3.962908 -5.305044) (xy -4.978908 -4.797044) (xy -4.978908 -5.813044)
			)
			(stroke
				(width 0)
				(type default)
			)
			(fill yes)
			(layer "F.SilkS")
		)
		(fp_line
			(start 3.750056 5.500116)
			(end 3.750056 -5.500116)
			(stroke
				(width 0.1)
				(type default)
			)
			(layer "F.Fab")
		)
		(fp_line
			(start 3.750056 -5.500116)
			(end -3.750056 -5.500116)
			(stroke
				(width 0.1)
				(type default)
			)
			(layer "F.Fab")
		)
		(fp_line
			(start -3.750056 5.500116)
			(end 3.750056 5.500116)
			(stroke
				(width 0.1)
				(type default)
			)
			(layer "F.Fab")
		)
		(fp_line
			(start -3.750056 -5.500116)
			(end -3.750056 5.500116)
			(stroke
				(width 0.1)
				(type default)
			)
			(layer "F.Fab")
		)
		(fp_poly
			(pts
				(xy -4.9276 -4.757928) (xy -4.9276 -3.741928) (xy -3.9116 -4.249928)
			)
			(stroke
				(width 0)
				(type default)
			)
			(fill yes)
			(layer "F.Fab")
		)
		(pad "1" smd rect
			(at 0 -4.249928 90)
			(size 2.413 4.5212)
			(layers "F.Cu" "F.Mask" "F.Paste")
			(net "SW_PVDDCR_CPU0_P0_SW6")
		)
		(pad "2" smd rect
			(at 0 -1.175004 90)
			(size 1.3716 4.5212)
			(layers "F.Cu" "F.Mask" "F.Paste")
			(net "IND_CPU0_P0_CPL0")
		)
		(pad "3" smd rect
			(at 0 1.175004 90)
			(size 1.3716 4.5212)
			(layers "F.Cu" "F.Mask" "F.Paste")
			(net "IND_CPU0_P0_CPL6")
		)
		(pad "4" smd rect
			(at 0 4.249928 90)
			(size 2.413 4.5212)
			(layers "F.Cu" "F.Mask" "F.Paste")
			(net "PVDDCR_CPU0_P0")
		)
	)
)
